# S9S_MB_2U (Grand Teton) — schematic netlist excerpt (pin names and nets, part order shuffled) for the footprints in the layout excerpt that follows; sources: Cadence DE-HDL packaged netlist, KiCad conversion of 03242023_DA0F0TMBIJ0_F0T_Motherboard_J_brd_V01_OCP.brd

C45  Q_CAP  10UF 16V 10% X6S  pkg C0805  page 96 : A = P12V_S3_AUX_CPU0_NVDIMM ; B = GND
PR306  Q_RES  28K 1% EMPTY  pkg 0402LF  page 284 : A = PVCCIN_CPU1_VREF ; B = PVCCIN_CPU1_ADDR
R26  Q_RES  10K 1% CHIP  pkg 0402LF  page 82 : A = PD_CHA_CPU0_DIMM1_SAA ; B = GND

(kicad_pcb
	(version 20260206)
	(generator "pcbnew")
	(generator_version "10.0")
	(general
		(thickness 1.6)
		(legacy_teardrops no)
	)
	(paper "A4")
	(title_block
		(title "03242023_DA0F0TMBIJ0_F0T_Motherboard_J_brd_V01_OCP.brd")
		(comment 1 "Grand Teton / footprints 4861-4863 of 6105")
	)
	(layers
		(0 "F.Cu" signal "TOP")
		(4 "In1.Cu" signal "GND")
		(6 "In2.Cu" signal "IN1")
		(8 "In3.Cu" signal "GND1")
		(10 "In4.Cu" signal "IN2")
		(12 "In5.Cu" signal "GND2")
		(14 "In6.Cu" signal "IN3")
		(16 "In7.Cu" signal "GND3")
		(18 "In8.Cu" signal "VCC")
		(20 "In9.Cu" signal "VCC1")
		(22 "In10.Cu" signal "GND4")
		(24 "In11.Cu" signal "IN4")
		(26 "In12.Cu" signal "GND5")
		(28 "In13.Cu" signal "IN5")
		(30 "In14.Cu" signal "GND6")
		(32 "In15.Cu" signal "IN6")
		(34 "In16.Cu" signal "GND7")
		(2 "B.Cu" signal "BOTTOM")
		(9 "F.Adhes" user "F.Adhesive")
		(11 "B.Adhes" user "B.Adhesive")
		(13 "F.Paste" user "Package Geometry/Pastemask Top")
		(15 "B.Paste" user "Package Geometry/Pastemask Bottom")
		(5 "F.SilkS" user "Ref Des/Silkscreen Top")
		(7 "B.SilkS" user "Ref Des/Silkscreen Bottom")
		(1 "F.Mask" user "Board Geometry/Soldermask Top")
		(3 "B.Mask" user "Board Geometry/Soldermask Bottom")
		(17 "Dwgs.User" user "User.Drawings")
		(19 "Cmts.User" user "User.Comments")
		(21 "Eco1.User" user "User.Eco1")
		(23 "Eco2.User" user "User.Eco2")
		(25 "Edge.Cuts" user "Board Geometry/Outline")
		(27 "Margin" user)
		(31 "F.CrtYd" user "Package Geometry/Place Bound Top")
		(29 "B.CrtYd" user "Package Geometry/Place Bound Bottom")
		(35 "F.Fab" user "Ref Des/Assembly Top")
		(33 "B.Fab" user "Ref Des/Assembly Bottom")
	)
	(footprint ""
		(layer "B.Cu")
		(at 114.369596 -357.436166)
		(property "Reference" "PR306"
			(at 0 0 0)
			(layer "B.SilkS")
			(hide yes)
			(effects
				(font
					(size 1.27 1.27)
				)
				(justify mirror)
			)
		)
		(property "Value" ""
			(at 0 0 0)
			(layer "B.Fab")
			(effects
				(font
					(size 1.27 1.27)
				)
				(justify mirror)
			)
		)
		(duplicate_pad_numbers_are_jumpers no)
		(fp_line
			(start -0.7874 -0.4064)
			(end -0.7874 0.4064)
			(stroke
				(width 0.1524)
				(type default)
			)
			(layer "B.SilkS")
		)
		(fp_line
			(start -0.7874 0.4064)
			(end 0.7874 0.4064)
			(stroke
				(width 0.1524)
				(type default)
			)
			(layer "B.SilkS")
		)
		(fp_line
			(start 0.7874 -0.4064)
			(end -0.7874 -0.4064)
			(stroke
				(width 0.1524)
				(type default)
			)
			(layer "B.SilkS")
		)
		(fp_line
			(start 0.7874 0.4064)
			(end 0.7874 -0.4064)
			(stroke
				(width 0.1524)
				(type default)
			)
			(layer "B.SilkS")
		)
		(fp_line
			(start -0.67945 -0.3048)
			(end -0.67945 0.3048)
			(stroke
				(width 0.1)
				(type default)
			)
			(layer "B.Fab")
		)
		(fp_line
			(start -0.67945 0.3048)
			(end -0.120396 0.3048)
			(stroke
				(width 0.1)
				(type default)
			)
			(layer "B.Fab")
		)
		(fp_line
			(start -0.12065 -0.3048)
			(end -0.67945 -0.3048)
			(stroke
				(width 0.1)
				(type default)
			)
			(layer "B.Fab")
		)
		(fp_line
			(start -0.12065 -0.2794)
			(end -0.12065 -0.3048)
			(stroke
				(width 0.1)
				(type default)
			)
			(layer "B.Fab")
		)
		(fp_line
			(start -0.120396 0.2794)
			(end 0.12065 0.2794)
			(stroke
				(width 0.1)
				(type default)
			)
			(layer "B.Fab")
		)
		(fp_line
			(start -0.120396 0.3048)
			(end -0.120396 0.2794)
			(stroke
				(width 0.1)
				(type default)
			)
			(layer "B.Fab")
		)
		(fp_line
			(start 0.12065 -0.305054)
			(end 0.12065 -0.2794)
			(stroke
				(width 0.1)
				(type default)
			)
			(layer "B.Fab")
		)
		(fp_line
			(start 0.12065 -0.2794)
			(end -0.12065 -0.2794)
			(stroke
				(width 0.1)
				(type default)
			)
			(layer "B.Fab")
		)
		(fp_line
			(start 0.12065 0.2794)
			(end 0.12065 0.3048)
			(stroke
				(width 0.1)
				(type default)
			)
			(layer "B.Fab")
		)
		(fp_line
			(start 0.12065 0.3048)
			(end 0.67945 0.3048)
			(stroke
				(width 0.1)
				(type default)
			)
			(layer "B.Fab")
		)
		(fp_line
			(start 0.67945 -0.305054)
			(end 0.12065 -0.305054)
			(stroke
				(width 0.1)
				(type default)
			)
			(layer "B.Fab")
		)
		(fp_line
			(start 0.67945 0.3048)
			(end 0.67945 -0.305054)
			(stroke
				(width 0.1)
				(type default)
			)
			(layer "B.Fab")
		)
		(pad "1" smd circle
			(at 0.40005 0 180)
			(size 0 0)
			(layers "B.Cu" "B.Mask" "B.Paste")
			(net "PVCCIN_CPU1_VREF")
		)
		(pad "2" smd circle
			(at -0.40005 0 180)
			(size 0 0)
			(layers "B.Cu" "B.Mask" "B.Paste")
			(net "PVCCIN_CPU1_ADDR")
		)
	)
	(footprint ""
		(layer "B.Cu")
		(at 459.572614 -321.549776 -90)
		(property "Reference" "C45"
			(at 0 0 90)
			(layer "B.SilkS")
			(hide yes)
			(effects
				(font
					(size 1.27 1.27)
				)
				(justify mirror)
			)
		)
		(property "Value" ""
			(at 0 0 90)
			(layer "B.Fab")
			(effects
				(font
					(size 1.27 1.27)
				)
				(justify mirror)
			)
		)
		(duplicate_pad_numbers_are_jumpers no)
		(fp_line
			(start -1.524 0.762)
			(end 1.524 0.762)
			(stroke
				(width 0.1524)
				(type default)
			)
			(layer "B.SilkS")
		)
		(fp_line
			(start 1.524 0.762)
			(end 1.524 -0.762)
			(stroke
				(width 0.1524)
				(type default)
			)
			(layer "B.SilkS")
		)
		(fp_line
			(start -1.524 -0.762)
			(end -1.524 0.762)
			(stroke
				(width 0.1524)
				(type default)
			)
			(layer "B.SilkS")
		)
		(fp_line
			(start 1.524 -0.762)
			(end -1.524 -0.762)
			(stroke
				(width 0.1524)
				(type default)
			)
			(layer "B.SilkS")
		)
		(fp_line
			(start -1.1049 0.724916)
			(end -1.1049 -0.724916)
			(stroke
				(width 0.1)
				(type default)
			)
			(layer "B.Fab")
		)
		(fp_line
			(start 1.1049 0.724916)
			(end -1.1049 0.724916)
			(stroke
				(width 0.1)
				(type default)
			)
			(layer "B.Fab")
		)
		(fp_line
			(start -1.1049 -0.724916)
			(end 1.1049 -0.724916)
			(stroke
				(width 0.1)
				(type default)
			)
			(layer "B.Fab")
		)
		(fp_line
			(start 1.1049 -0.724916)
			(end 1.1049 0.724916)
			(stroke
				(width 0.1)
				(type default)
			)
			(layer "B.Fab")
		)
		(pad "1" smd rect
			(at 0.889 0 270)
			(size 1.016 1.27)
			(layers "B.Cu" "B.Mask" "B.Paste")
			(net "P12V_S3_AUX_CPU0_NVDIMM")
		)
		(pad "2" smd rect
			(at -0.889 0 270)
			(size 1.016 1.27)
			(layers "B.Cu" "B.Mask" "B.Paste")
			(net "GND")
		)
	)
	(footprint ""
		(layer "B.Cu")
		(at 303.149254 -319.05956)
		(property "Reference" "R26"
			(at 0 0 0)
			(layer "B.SilkS")
			(hide yes)
			(effects
				(font
					(size 1.27 1.27)
				)
				(justify mirror)
			)
		)
		(property "Value" ""
			(at 0 0 0)
			(layer "B.Fab")
			(effects
				(font
					(size 1.27 1.27)
				)
				(justify mirror)
			)
		)
		(duplicate_pad_numbers_are_jumpers no)
		(fp_line
			(start -0.7874 -0.4064)
			(end -0.7874 0.4064)
			(stroke
				(width 0.1524)
				(type default)
			)
			(layer "B.SilkS")
		)
		(fp_line
			(start -0.7874 0.4064)
			(end 0.7874 0.4064)
			(stroke
				(width 0.1524)
				(type default)
			)
			(layer "B.SilkS")
		)
		(fp_line
			(start 0.7874 -0.4064)
			(end -0.7874 -0.4064)
			(stroke
				(width 0.1524)
				(type default)
			)
			(layer "B.SilkS")
		)
		(fp_line
			(start 0.7874 0.4064)
			(end 0.7874 -0.4064)
			(stroke
				(width 0.1524)
				(type default)
			)
			(layer "B.SilkS")
		)
		(fp_line
			(start -0.67945 -0.3048)
			(end -0.67945 0.3048)
			(stroke
				(width 0.1)
				(type default)
			)
			(layer "B.Fab")
		)
		(fp_line
			(start -0.67945 0.3048)
			(end -0.120396 0.3048)
			(stroke
				(width 0.1)
				(type default)
			)
			(layer "B.Fab")
		)
		(fp_line
			(start -0.12065 -0.3048)
			(end -0.67945 -0.3048)
			(stroke
				(width 0.1)
				(type default)
			)
			(layer "B.Fab")
		)
		(fp_line
			(start -0.12065 -0.2794)
			(end -0.12065 -0.3048)
			(stroke
				(width 0.1)
				(type default)
			)
			(layer "B.Fab")
		)
		(fp_line
			(start -0.120396 0.2794)
			(end 0.12065 0.2794)
			(stroke
				(width 0.1)
				(type default)
			)
			(layer "B.Fab")
		)
		(fp_line
			(start -0.120396 0.3048)
			(end -0.120396 0.2794)
			(stroke
				(width 0.1)
				(type default)
			)
			(layer "B.Fab")
		)
		(fp_line
			(start 0.12065 -0.305054)
			(end 0.12065 -0.2794)
			(stroke
				(width 0.1)
				(type default)
			)
			(layer "B.Fab")
		)
		(fp_line
			(start 0.12065 -0.2794)
			(end -0.12065 -0.2794)
			(stroke
				(width 0.1)
				(type default)
			)
			(layer "B.Fab")
		)
		(fp_line
			(start 0.12065 0.2794)
			(end 0.12065 0.3048)
			(stroke
				(width 0.1)
				(type default)
			)
			(layer "B.Fab")
		)
		(fp_line
			(start 0.12065 0.3048)
			(end 0.67945 0.3048)
			(stroke
				(width 0.1)
				(type default)
			)
			(layer "B.Fab")
		)
		(fp_line
			(start 0.67945 -0.305054)
			(end 0.12065 -0.305054)
			(stroke
				(width 0.1)
				(type default)
			)
			(layer "B.Fab")
		)
		(fp_line
			(start 0.67945 0.3048)
			(end 0.67945 -0.305054)
			(stroke
				(width 0.1)
				(type default)
			)
			(layer "B.Fab")
		)
		(pad "1" smd circle
			(at 0.40005 0 180)
			(size 0 0)
			(layers "B.Cu" "B.Mask" "B.Paste")
			(net "PD_CHA_CPU0_DIMM1_SAA")
		)
		(pad "2" smd circle
			(at -0.40005 0 180)
			(size 0 0)
			(layers "B.Cu" "B.Mask" "B.Paste")
			(net "GND")
		)
	)
)
